(kicad_pcb
	(version 20260206)
	(generator "pcbnew")
	(generator_version "10.0")
	(general
		(thickness 1.6)
		(legacy_teardrops no)
	)
	(paper "A4")
	(title_block
		(title "04192023_DAF0TMB3IC0_F0TG_MB_C_brd_V02_OCP.brd")
		(comment 1 "Grand Teton / footprints 811-817 of 8354")
	)
	(layers
		(0 "F.Cu" signal "TOP")
		(4 "In1.Cu" signal "GND")
		(6 "In2.Cu" signal "IN1")
		(8 "In3.Cu" signal "GND1")
		(10 "In4.Cu" signal "IN2")
		(12 "In5.Cu" signal "GND2")
		(14 "In6.Cu" signal "IN3")
		(16 "In7.Cu" signal "GND3")
		(18 "In8.Cu" signal "VCC")
		(20 "In9.Cu" signal "VCC1")
		(22 "In10.Cu" signal "GND4")
		(24 "In11.Cu" signal "IN4")
		(26 "In12.Cu" signal "GND5")
		(28 "In13.Cu" signal "IN5")
		(30 "In14.Cu" signal "GND6")
		(32 "In15.Cu" signal "IN6")
		(34 "In16.Cu" signal "GND7")
		(2 "B.Cu" signal "BOTTOM")
		(9 "F.Adhes" user "F.Adhesive")
		(11 "B.Adhes" user "B.Adhesive")
		(13 "F.Paste" user "Package Geometry/Pastemask Top")
		(15 "B.Paste" user "Package Geometry/Pastemask Bottom")
		(5 "F.SilkS" user "Ref Des/Silkscreen Top")
		(7 "B.SilkS" user "Ref Des/Silkscreen Bottom")
		(1 "F.Mask" user "Board Geometry/Soldermask Top")
		(3 "B.Mask" user "Board Geometry/Soldermask Bottom")
		(17 "Dwgs.User" user "User.Drawings")
		(19 "Cmts.User" user "User.Comments")
		(21 "Eco1.User" user "User.Eco1")
		(23 "Eco2.User" user "User.Eco2")
		(25 "Edge.Cuts" user "Board Geometry/Outline")
		(27 "Margin" user)
		(31 "F.CrtYd" user "Package Geometry/Place Bound Top")
		(29 "B.CrtYd" user "Package Geometry/Place Bound Bottom")
		(35 "F.Fab" user "Ref Des/Assembly Top")
		(33 "B.Fab" user "Ref Des/Assembly Bottom")
	)
	(footprint ""
		(layer "F.Cu")
		(at 368.600736 -403.818852 -90)
		(property "Reference" "R1122"
			(at 0 0 270)
			(layer "F.SilkS")
			(hide yes)
			(effects
				(font
					(size 1.27 1.27)
				)
			)
		)
		(property "Value" ""
			(at 0 0 270)
			(layer "F.Fab")
			(effects
				(font
					(size 1.27 1.27)
				)
			)
		)
		(duplicate_pad_numbers_are_jumpers no)
		(fp_line
			(start -0.32512 0.175006)
			(end -0.32512 -0.175006)
			(stroke
				(width 0.1)
				(type default)
			)
			(layer "F.Fab")
		)
		(fp_line
			(start 0.32512 0.175006)
			(end -0.32512 0.175006)
			(stroke
				(width 0.1)
				(type default)
			)
			(layer "F.Fab")
		)
		(fp_line
			(start -0.32512 -0.175006)
			(end 0.32512 -0.175006)
			(stroke
				(width 0.1)
				(type default)
			)
			(layer "F.Fab")
		)
		(fp_line
			(start 0.32512 -0.175006)
			(end 0.32512 0.175006)
			(stroke
				(width 0.1)
				(type default)
			)
			(layer "F.Fab")
		)
		(pad "1" smd rect
			(at -0.2667 0 270)
			(size 0.3048 0.381)
			(layers "F.Cu" "F.Mask" "F.Paste")
			(net "P1V8_CPU0_RT_1D")
		)
		(pad "2" smd rect
			(at 0.2667 0 90)
			(size 0.3048 0.381)
			(layers "F.Cu" "F.Mask" "F.Paste")
			(net "MODE_RT_CPU0_P3")
		)
	)
	(footprint ""
		(layer "F.Cu")
		(at 147.16379 -102.294182 90)
		(property "Reference" "C2007"
			(at 0 0 90)
			(layer "F.SilkS")
			(hide yes)
			(effects
				(font
					(size 1.27 1.27)
				)
			)
		)
		(property "Value" ""
			(at 0 0 90)
			(layer "F.Fab")
			(effects
				(font
					(size 1.27 1.27)
				)
			)
		)
		(duplicate_pad_numbers_are_jumpers no)
		(fp_line
			(start 0.7874 -0.4064)
			(end 0.7874 0.4064)
			(stroke
				(width 0.1524)
				(type default)
			)
			(layer "F.SilkS")
		)
		(fp_line
			(start -0.7874 -0.4064)
			(end 0.7874 -0.4064)
			(stroke
				(width 0.1524)
				(type default)
			)
			(layer "F.SilkS")
		)
		(fp_line
			(start 0.7874 0.4064)
			(end -0.7874 0.4064)
			(stroke
				(width 0.1524)
				(type default)
			)
			(layer "F.SilkS")
		)
		(fp_line
			(start -0.7874 0.4064)
			(end -0.7874 -0.4064)
			(stroke
				(width 0.1524)
				(type default)
			)
			(layer "F.SilkS")
		)
		(fp_line
			(start -0.12065 -0.305054)
			(end -0.12065 -0.2794)
			(stroke
				(width 0.1)
				(type default)
			)
			(layer "F.Fab")
		)
		(fp_line
			(start -0.67945 -0.305054)
			(end -0.12065 -0.305054)
			(stroke
				(width 0.1)
				(type default)
			)
			(layer "F.Fab")
		)
		(fp_line
			(start 0.67945 -0.3048)
			(end 0.67945 0.3048)
			(stroke
				(width 0.1)
				(type default)
			)
			(layer "F.Fab")
		)
		(fp_line
			(start 0.12065 -0.3048)
			(end 0.67945 -0.3048)
			(stroke
				(width 0.1)
				(type default)
			)
			(layer "F.Fab")
		)
		(fp_line
			(start 0.12065 -0.2794)
			(end 0.12065 -0.3048)
			(stroke
				(width 0.1)
				(type default)
			)
			(layer "F.Fab")
		)
		(fp_line
			(start -0.12065 -0.2794)
			(end 0.12065 -0.2794)
			(stroke
				(width 0.1)
				(type default)
			)
			(layer "F.Fab")
		)
		(fp_line
			(start 0.120396 0.2794)
			(end -0.12065 0.2794)
			(stroke
				(width 0.1)
				(type default)
			)
			(layer "F.Fab")
		)
		(fp_line
			(start -0.12065 0.2794)
			(end -0.12065 0.3048)
			(stroke
				(width 0.1)
				(type default)
			)
			(layer "F.Fab")
		)
		(fp_line
			(start 0.67945 0.3048)
			(end 0.120396 0.3048)
			(stroke
				(width 0.1)
				(type default)
			)
			(layer "F.Fab")
		)
		(fp_line
			(start 0.120396 0.3048)
			(end 0.120396 0.2794)
			(stroke
				(width 0.1)
				(type default)
			)
			(layer "F.Fab")
		)
		(fp_line
			(start -0.12065 0.3048)
			(end -0.67945 0.3048)
			(stroke
				(width 0.1)
				(type default)
			)
			(layer "F.Fab")
		)
		(fp_line
			(start -0.67945 0.3048)
			(end -0.67945 -0.305054)
			(stroke
				(width 0.1)
				(type default)
			)
			(layer "F.Fab")
		)
		(pad "1" smd circle
			(at -0.40005 0 90)
			(size 0 0)
			(layers "F.Cu" "F.Mask" "F.Paste")
			(net "P3V3_AUX")
		)
		(pad "2" smd circle
			(at 0.40005 0 90)
			(size 0 0)
			(layers "F.Cu" "F.Mask" "F.Paste")
			(net "GND")
		)
	)
	(footprint ""
		(layer "F.Cu")
		(at 90.209878 -142.85341)
		(property "Reference" "R8179"
			(at 0 0 0)
			(layer "F.SilkS")
			(hide yes)
			(effects
				(font
					(size 1.27 1.27)
				)
			)
		)
		(property "Value" ""
			(at 0 0 0)
			(layer "F.Fab")
			(effects
				(font
					(size 1.27 1.27)
				)
			)
		)
		(duplicate_pad_numbers_are_jumpers no)
		(fp_line
			(start -0.7874 -0.4064)
			(end 0.7874 -0.4064)
			(stroke
				(width 0.1524)
				(type default)
			)
			(layer "F.SilkS")
		)
		(fp_line
			(start -0.7874 0.4064)
			(end -0.7874 -0.4064)
			(stroke
				(width 0.1524)
				(type default)
			)
			(layer "F.SilkS")
		)
		(fp_line
			(start 0.7874 -0.4064)
			(end 0.7874 0.4064)
			(stroke
				(width 0.1524)
				(type default)
			)
			(layer "F.SilkS")
		)
		(fp_line
			(start 0.7874 0.4064)
			(end -0.7874 0.4064)
			(stroke
				(width 0.1524)
				(type default)
			)
			(layer "F.SilkS")
		)
		(fp_line
			(start -0.67945 -0.305054)
			(end -0.12065 -0.305054)
			(stroke
				(width 0.1)
				(type default)
			)
			(layer "F.Fab")
		)
		(fp_line
			(start -0.67945 0.3048)
			(end -0.67945 -0.305054)
			(stroke
				(width 0.1)
				(type default)
			)
			(layer "F.Fab")
		)
		(fp_line
			(start -0.12065 -0.305054)
			(end -0.12065 -0.2794)
			(stroke
				(width 0.1)
				(type default)
			)
			(layer "F.Fab")
		)
		(fp_line
			(start -0.12065 -0.2794)
			(end 0.12065 -0.2794)
			(stroke
				(width 0.1)
				(type default)
			)
			(layer "F.Fab")
		)
		(fp_line
			(start -0.12065 0.2794)
			(end -0.12065 0.3048)
			(stroke
				(width 0.1)
				(type default)
			)
			(layer "F.Fab")
		)
		(fp_line
			(start -0.12065 0.3048)
			(end -0.67945 0.3048)
			(stroke
				(width 0.1)
				(type default)
			)
			(layer "F.Fab")
		)
		(fp_line
			(start 0.120396 0.2794)
			(end -0.12065 0.2794)
			(stroke
				(width 0.1)
				(type default)
			)
			(layer "F.Fab")
		)
		(fp_line
			(start 0.120396 0.3048)
			(end 0.120396 0.2794)
			(stroke
				(width 0.1)
				(type default)
			)
			(layer "F.Fab")
		)
		(fp_line
			(start 0.12065 -0.3048)
			(end 0.67945 -0.3048)
			(stroke
				(width 0.1)
				(type default)
			)
			(layer "F.Fab")
		)
		(fp_line
			(start 0.12065 -0.2794)
			(end 0.12065 -0.3048)
			(stroke
				(width 0.1)
				(type default)
			)
			(layer "F.Fab")
		)
		(fp_line
			(start 0.67945 -0.3048)
			(end 0.67945 0.3048)
			(stroke
				(width 0.1)
				(type default)
			)
			(layer "F.Fab")
		)
		(fp_line
			(start 0.67945 0.3048)
			(end 0.120396 0.3048)
			(stroke
				(width 0.1)
				(type default)
			)
			(layer "F.Fab")
		)
		(pad "1" smd circle
			(at -0.40005 0)
			(size 0 0)
			(layers "F.Cu" "F.Mask" "F.Paste")
			(net "PVDDCR_CPU0_P1_EN")
		)
		(pad "2" smd circle
			(at 0.40005 0)
			(size 0 0)
			(layers "F.Cu" "F.Mask" "F.Paste")
			(net "PVDDCR_CPU0_P1_EN_R")
		)
	)
	(footprint ""
		(layer "F.Cu")
		(at 11.421618 -106.28249 -90)
		(property "Reference" "R2788"
			(at 0 0 270)
			(layer "F.SilkS")
			(hide yes)
			(effects
				(font
					(size 1.27 1.27)
				)
			)
		)
		(property "Value" ""
			(at 0 0 270)
			(layer "F.Fab")
			(effects
				(font
					(size 1.27 1.27)
				)
			)
		)
		(duplicate_pad_numbers_are_jumpers no)
		(fp_line
			(start -0.7874 0.4064)
			(end -0.7874 -0.4064)
			(stroke
				(width 0.1524)
				(type default)
			)
			(layer "F.SilkS")
		)
		(fp_line
			(start 0.7874 0.4064)
			(end -0.7874 0.4064)
			(stroke
				(width 0.1524)
				(type default)
			)
			(layer "F.SilkS")
		)
		(fp_line
			(start -0.7874 -0.4064)
			(end 0.7874 -0.4064)
			(stroke
				(width 0.1524)
				(type default)
			)
			(layer "F.SilkS")
		)
		(fp_line
			(start 0.7874 -0.4064)
			(end 0.7874 0.4064)
			(stroke
				(width 0.1524)
				(type default)
			)
			(layer "F.SilkS")
		)
		(fp_line
			(start -0.67945 0.3048)
			(end -0.67945 -0.305054)
			(stroke
				(width 0.1)
				(type default)
			)
			(layer "F.Fab")
		)
		(fp_line
			(start -0.12065 0.3048)
			(end -0.67945 0.3048)
			(stroke
				(width 0.1)
				(type default)
			)
			(layer "F.Fab")
		)
		(fp_line
			(start 0.120396 0.3048)
			(end 0.120396 0.2794)
			(stroke
				(width 0.1)
				(type default)
			)
			(layer "F.Fab")
		)
		(fp_line
			(start 0.67945 0.3048)
			(end 0.120396 0.3048)
			(stroke
				(width 0.1)
				(type default)
			)
			(layer "F.Fab")
		)
		(fp_line
			(start -0.12065 0.2794)
			(end -0.12065 0.3048)
			(stroke
				(width 0.1)
				(type default)
			)
			(layer "F.Fab")
		)
		(fp_line
			(start 0.120396 0.2794)
			(end -0.12065 0.2794)
			(stroke
				(width 0.1)
				(type default)
			)
			(layer "F.Fab")
		)
		(fp_line
			(start -0.12065 -0.2794)
			(end 0.12065 -0.2794)
			(stroke
				(width 0.1)
				(type default)
			)
			(layer "F.Fab")
		)
		(fp_line
			(start 0.12065 -0.2794)
			(end 0.12065 -0.3048)
			(stroke
				(width 0.1)
				(type default)
			)
			(layer "F.Fab")
		)
		(fp_line
			(start 0.12065 -0.3048)
			(end 0.67945 -0.3048)
			(stroke
				(width 0.1)
				(type default)
			)
			(layer "F.Fab")
		)
		(fp_line
			(start 0.67945 -0.3048)
			(end 0.67945 0.3048)
			(stroke
				(width 0.1)
				(type default)
			)
			(layer "F.Fab")
		)
		(fp_line
			(start -0.67945 -0.305054)
			(end -0.12065 -0.305054)
			(stroke
				(width 0.1)
				(type default)
			)
			(layer "F.Fab")
		)
		(fp_line
			(start -0.12065 -0.305054)
			(end -0.12065 -0.2794)
			(stroke
				(width 0.1)
				(type default)
			)
			(layer "F.Fab")
		)
		(pad "1" smd rect
			(at -0.40005 0 90)
			(size 0.4572 0.508)
			(layers "F.Cu" "F.Mask" "F.Paste")
			(net "USB2_HOST_BMC_B_BUF_DP")
		)
		(pad "2" smd rect
			(at 0.40005 0 90)
			(size 0.4572 0.508)
			(layers "F.Cu" "F.Mask" "F.Paste")
			(net "USB2_HUB_BUF_SWB_R_DP")
		)
	)
	(footprint ""
		(layer "F.Cu")
		(at 1.551686 -424.956732)
		(property "Reference" "BIOS_LABEL"
			(at -2.487168 2.245106 90)
			(unlocked yes)
			(layer "F.SilkS")
			(effects
				(font
					(size 0.7874 0.5842)
					(thickness 0.1524)
				)
				(justify left)
			)
		)
		(property "Value" ""
			(at 0 0 0)
			(layer "F.Fab")
			(effects
				(font
					(size 1.27 1.27)
				)
			)
		)
		(duplicate_pad_numbers_are_jumpers no)
		(pad "1" smd circle
			(at 0 0)
			(size 0.762 0.762)
			(layers "F.Cu" "F.Mask" "F.Paste")
			(net "Net_2230")
		)
	)
	(footprint ""
		(layer "F.Cu")
		(at 9.908032 -92.687648 90)
		(property "Reference" "R3654"
			(at 0 0 90)
			(layer "F.SilkS")
			(hide yes)
			(effects
				(font
					(size 1.27 1.27)
				)
			)
		)
		(property "Value" ""
			(at 0 0 90)
			(layer "F.Fab")
			(effects
				(font
					(size 1.27 1.27)
				)
			)
		)
		(duplicate_pad_numbers_are_jumpers no)
		(fp_line
			(start 0.7874 -0.4064)
			(end 0.7874 0.4064)
			(stroke
				(width 0.1524)
				(type default)
			)
			(layer "F.SilkS")
		)
		(fp_line
			(start -0.7874 -0.4064)
			(end 0.7874 -0.4064)
			(stroke
				(width 0.1524)
				(type default)
			)
			(layer "F.SilkS")
		)
		(fp_line
			(start 0.7874 0.4064)
			(end -0.7874 0.4064)
			(stroke
				(width 0.1524)
				(type default)
			)
			(layer "F.SilkS")
		)
		(fp_line
			(start -0.7874 0.4064)
			(end -0.7874 -0.4064)
			(stroke
				(width 0.1524)
				(type default)
			)
			(layer "F.SilkS")
		)
		(fp_line
			(start -0.12065 -0.305054)
			(end -0.12065 -0.2794)
			(stroke
				(width 0.1)
				(type default)
			)
			(layer "F.Fab")
		)
		(fp_line
			(start -0.67945 -0.305054)
			(end -0.12065 -0.305054)
			(stroke
				(width 0.1)
				(type default)
			)
			(layer "F.Fab")
		)
		(fp_line
			(start 0.67945 -0.3048)
			(end 0.67945 0.3048)
			(stroke
				(width 0.1)
				(type default)
			)
			(layer "F.Fab")
		)
		(fp_line
			(start 0.12065 -0.3048)
			(end 0.67945 -0.3048)
			(stroke
				(width 0.1)
				(type default)
			)
			(layer "F.Fab")
		)
		(fp_line
			(start 0.12065 -0.2794)
			(end 0.12065 -0.3048)
			(stroke
				(width 0.1)
				(type default)
			)
			(layer "F.Fab")
		)
		(fp_line
			(start -0.12065 -0.2794)
			(end 0.12065 -0.2794)
			(stroke
				(width 0.1)
				(type default)
			)
			(layer "F.Fab")
		)
		(fp_line
			(start 0.120396 0.2794)
			(end -0.12065 0.2794)
			(stroke
				(width 0.1)
				(type default)
			)
			(layer "F.Fab")
		)
		(fp_line
			(start -0.12065 0.2794)
			(end -0.12065 0.3048)
			(stroke
				(width 0.1)
				(type default)
			)
			(layer "F.Fab")
		)
		(fp_line
			(start 0.67945 0.3048)
			(end 0.120396 0.3048)
			(stroke
				(width 0.1)
				(type default)
			)
			(layer "F.Fab")
		)
		(fp_line
			(start 0.120396 0.3048)
			(end 0.120396 0.2794)
			(stroke
				(width 0.1)
				(type default)
			)
			(layer "F.Fab")
		)
		(fp_line
			(start -0.12065 0.3048)
			(end -0.67945 0.3048)
			(stroke
				(width 0.1)
				(type default)
			)
			(layer "F.Fab")
		)
		(fp_line
			(start -0.67945 0.3048)
			(end -0.67945 -0.305054)
			(stroke
				(width 0.1)
				(type default)
			)
			(layer "F.Fab")
		)
		(pad "1" smd circle
			(at -0.40005 0 90)
			(size 0 0)
			(layers "F.Cu" "F.Mask" "F.Paste")
			(net "RST_USB_HUB_N")
		)
		(pad "2" smd circle
			(at 0.40005 0 90)
			(size 0 0)
			(layers "F.Cu" "F.Mask" "F.Paste")
			(net "RST_USB_HUB_R_N")
		)
	)
	(footprint ""
		(layer "F.Cu")
		(at 111.477044 -261.748016 -90)
		(property "Reference" "C2113"
			(at 0 0 270)
			(layer "F.SilkS")
			(hide yes)
			(effects
				(font
					(size 1.27 1.27)
				)
			)
		)
		(property "Value" ""
			(at 0 0 270)
			(layer "F.Fab")
			(effects
				(font
					(size 1.27 1.27)
				)
			)
		)
		(duplicate_pad_numbers_are_jumpers no)
		(fp_line
			(start -0.7874 0.4064)
			(end -0.7874 -0.4064)
			(stroke
				(width 0.1524)
				(type default)
			)
			(layer "F.SilkS")
		)
		(fp_line
			(start 0.7874 0.4064)
			(end -0.7874 0.4064)
			(stroke
				(width 0.1524)
				(type default)
			)
			(layer "F.SilkS")
		)
		(fp_line
			(start -0.7874 -0.4064)
			(end 0.7874 -0.4064)
			(stroke
				(width 0.1524)
				(type default)
			)
			(layer "F.SilkS")
		)
		(fp_line
			(start 0.7874 -0.4064)
			(end 0.7874 0.4064)
			(stroke
				(width 0.1524)
				(type default)
			)
			(layer "F.SilkS")
		)
		(fp_line
			(start -0.67945 0.3048)
			(end -0.67945 -0.305054)
			(stroke
				(width 0.1)
				(type default)
			)
			(layer "F.Fab")
		)
		(fp_line
			(start -0.12065 0.3048)
			(end -0.67945 0.3048)
			(stroke
				(width 0.1)
				(type default)
			)
			(layer "F.Fab")
		)
		(fp_line
			(start 0.120396 0.3048)
			(end 0.120396 0.2794)
			(stroke
				(width 0.1)
				(type default)
			)
			(layer "F.Fab")
		)
		(fp_line
			(start 0.67945 0.3048)
			(end 0.120396 0.3048)
			(stroke
				(width 0.1)
				(type default)
			)
			(layer "F.Fab")
		)
		(fp_line
			(start -0.12065 0.2794)
			(end -0.12065 0.3048)
			(stroke
				(width 0.1)
				(type default)
			)
			(layer "F.Fab")
		)
		(fp_line
			(start 0.120396 0.2794)
			(end -0.12065 0.2794)
			(stroke
				(width 0.1)
				(type default)
			)
			(layer "F.Fab")
		)
		(fp_line
			(start -0.12065 -0.2794)
			(end 0.12065 -0.2794)
			(stroke
				(width 0.1)
				(type default)
			)
			(layer "F.Fab")
		)
		(fp_line
			(start 0.12065 -0.2794)
			(end 0.12065 -0.3048)
			(stroke
				(width 0.1)
				(type default)
			)
			(layer "F.Fab")
		)
		(fp_line
			(start 0.12065 -0.3048)
			(end 0.67945 -0.3048)
			(stroke
				(width 0.1)
				(type default)
			)
			(layer "F.Fab")
		)
		(fp_line
			(start 0.67945 -0.3048)
			(end 0.67945 0.3048)
			(stroke
				(width 0.1)
				(type default)
			)
			(layer "F.Fab")
		)
		(fp_line
			(start -0.67945 -0.305054)
			(end -0.12065 -0.305054)
			(stroke
				(width 0.1)
				(type default)
			)
			(layer "F.Fab")
		)
		(fp_line
			(start -0.12065 -0.305054)
			(end -0.12065 -0.2794)
			(stroke
				(width 0.1)
				(type default)
			)
			(layer "F.Fab")
		)
		(pad "1" smd circle
			(at -0.40005 0 270)
			(size 0 0)
			(layers "F.Cu" "F.Mask" "F.Paste")
			(net "PVDD11_S3_P1")
		)
		(pad "2" smd circle
			(at 0.40005 0 270)
			(size 0 0)
			(layers "F.Cu" "F.Mask" "F.Paste")
			(net "GND")
		)
	)
)
